FILE_TYPE=LIBRARY_PARTS;
TIME=' Created/Modified on Fri Aug 28 08:04:10 1998' ;
primitive 'TTL1G08','TTL1G08_SM';
  pin
    'Y'<0>:
      PIN_NUMBER='(4)';
      OUTPUT_LOAD='(20.0,-1.0)';
    'A'<0>:
      PIN_NUMBER='(1)';
      INPUT_LOAD='(-0.6,0.005)';
      PIN_GROUP='1';
    'B'<0>:
      PIN_NUMBER='(2)';
      INPUT_LOAD='(-0.6,0.005)';
      PIN_GROUP='1';
  end_pin;
  body
    POWER_PINS='(VCC:5;GND:3)';
    CLASS='IC';
    BODY_NAME='TTL1G08';
    PART_NAME='TTL1G08';
    PHYS_DES_PREFIX='U';
  end_body;
end_primitive;
END.
